(kicad_pcb
	(version 20260206)
	(generator "pcbnew")
	(generator_version "10.0")
	(general
		(thickness 1.6)
		(legacy_teardrops no)
	)
	(paper "A4")
	(title_block
		(title "v1-chassis-manager — T6M_CM_d_v01_1031_1645.brd")
		(comment 1 "Open CloudServer (Microsoft) / footprints 433-435 of 2512")
	)
	(layers
		(0 "F.Cu" signal "TOP")
		(4 "In1.Cu" signal "GND1")
		(6 "In2.Cu" signal "IN1")
		(8 "In3.Cu" signal "VCC1")
		(10 "In4.Cu" signal "VCC2")
		(12 "In5.Cu" signal "GND2")
		(14 "In6.Cu" signal "IN2")
		(16 "In7.Cu" signal "IN3")
		(18 "In8.Cu" signal "GND3")
		(2 "B.Cu" signal "BOTTOM")
		(9 "F.Adhes" user "F.Adhesive")
		(11 "B.Adhes" user "B.Adhesive")
		(13 "F.Paste" user "Package Geometry/Pastemask Top")
		(15 "B.Paste" user "Package Geometry/Pastemask Bottom")
		(5 "F.SilkS" user "Ref Des/Silkscreen Top")
		(7 "B.SilkS" user "Ref Des/Silkscreen Bottom")
		(1 "F.Mask" user "Board Geometry/Soldermask Top")
		(3 "B.Mask" user "Board Geometry/Soldermask Bottom")
		(17 "Dwgs.User" user "User.Drawings")
		(19 "Cmts.User" user "User.Comments")
		(21 "Eco1.User" user "User.Eco1")
		(23 "Eco2.User" user "User.Eco2")
		(25 "Edge.Cuts" user "Board Geometry/Outline")
		(27 "Margin" user)
		(31 "F.CrtYd" user "Package Geometry/Place Bound Top")
		(29 "B.CrtYd" user "Package Geometry/Place Bound Bottom")
		(35 "F.Fab" user "Ref Des/Assembly Top")
		(33 "B.Fab" user "Ref Des/Assembly Bottom")
	)
	(footprint ""
		(layer "F.Cu")
		(at 114.621564 -135.219186 180)
		(property "Reference" "PC102"
			(at -5.453888 2.098294 90)
			(unlocked yes)
			(layer "F.SilkS")
			(effects
				(font
					(size 0.635 0.4064)
					(thickness 0.1524)
				)
				(justify left)
			)
		)
		(property "Value" ""
			(at 0 0 180)
			(layer "F.Fab")
			(effects
				(font
					(size 1.27 1.27)
				)
			)
		)
		(duplicate_pad_numbers_are_jumpers no)
		(fp_line
			(start 0.7874 0.4064)
			(end -0.7874 0.4064)
			(stroke
				(width 0.1524)
				(type default)
			)
			(layer "F.SilkS")
		)
		(fp_line
			(start 0.7874 -0.4064)
			(end 0.7874 0.4064)
			(stroke
				(width 0.1524)
				(type default)
			)
			(layer "F.SilkS")
		)
		(fp_line
			(start 0 0.381)
			(end 0 -0.381)
			(stroke
				(width 0.1524)
				(type default)
			)
			(layer "F.SilkS")
		)
		(fp_line
			(start -0.7874 0.4064)
			(end -0.7874 -0.4064)
			(stroke
				(width 0.1524)
				(type default)
			)
			(layer "F.SilkS")
		)
		(fp_line
			(start -0.7874 -0.4064)
			(end 0.7874 -0.4064)
			(stroke
				(width 0.1524)
				(type default)
			)
			(layer "F.SilkS")
		)
		(fp_poly
			(pts
				(xy -0.5334 0.254) (xy -0.635 0.254) (xy -0.635 0.2286) (xy -0.635 -0.254) (xy -0.5334 -0.254) (xy -0.5334 -0.2794)
				(xy 0.5334 -0.2794) (xy 0.5334 -0.254) (xy 0.635 -0.254) (xy 0.635 0.254) (xy 0.5334 0.254) (xy 0.5334 0.2794)
				(xy -0.508 0.2794) (xy -0.5334 0.2794)
			)
			(stroke
				(width 0)
				(type default)
			)
			(fill no)
			(layer "F.CrtYd")
		)
		(pad "1" smd rect
			(at 0.40005 0 180)
			(size 0.4572 0.508)
			(layers "F.Cu" "F.Mask" "F.Paste")
			(net "VR_PVCCP_NODE1_COMP")
		)
		(pad "2" smd rect
			(at -0.40005 0 180)
			(size 0.4572 0.508)
			(layers "F.Cu" "F.Mask" "F.Paste")
			(net "VR_PVCCP_NODE1_COMP_RC")
		)
	)
	(footprint ""
		(layer "F.Cu")
		(at 178.025044 -163.517072 90)
		(property "Reference" "U138"
			(at 6.093206 3.490976 0)
			(unlocked yes)
			(layer "F.SilkS")
			(effects
				(font
					(size 0.7874 0.5842)
					(thickness 0.1524)
				)
				(justify left)
			)
		)
		(property "Value" ""
			(at 0 0 90)
			(layer "F.Fab")
			(effects
				(font
					(size 1.27 1.27)
				)
			)
		)
		(duplicate_pad_numbers_are_jumpers no)
		(fp_line
			(start 3.564128 -7.800086)
			(end 3.564128 7.800086)
			(stroke
				(width 0.1524)
				(type default)
			)
			(layer "F.SilkS")
		)
		(fp_line
			(start 1.800098 -7.800086)
			(end 3.564128 -7.800086)
			(stroke
				(width 0.1524)
				(type default)
			)
			(layer "F.SilkS")
		)
		(fp_line
			(start -1.800098 -7.800086)
			(end 0 -5.999988)
			(stroke
				(width 0.1524)
				(type default)
			)
			(layer "F.SilkS")
		)
		(fp_line
			(start -3.564128 -7.800086)
			(end -1.800098 -7.800086)
			(stroke
				(width 0.1524)
				(type default)
			)
			(layer "F.SilkS")
		)
		(fp_line
			(start 0 -5.999988)
			(end 1.800098 -7.800086)
			(stroke
				(width 0.1524)
				(type default)
			)
			(layer "F.SilkS")
		)
		(fp_line
			(start 3.564128 7.800086)
			(end -3.564128 7.800086)
			(stroke
				(width 0.1524)
				(type default)
			)
			(layer "F.SilkS")
		)
		(fp_line
			(start -3.564128 7.800086)
			(end -3.564128 -7.800086)
			(stroke
				(width 0.1524)
				(type default)
			)
			(layer "F.SilkS")
		)
		(fp_poly
			(pts
				(xy -3.70459 -9.133586) (xy -4.72059 -9.133586) (xy -4.21259 -8.117586)
			)
			(stroke
				(width 0)
				(type default)
			)
			(fill yes)
			(layer "F.SilkS")
		)
		(fp_poly
			(pts
				(xy -4.249928 7.800086) (xy -4.249928 7.4422) (xy -5.300472 7.4422) (xy -5.300472 -7.4422) (xy -4.249928 -7.4422)
				(xy -4.249928 -7.800086) (xy 4.249928 -7.800086) (xy 4.249928 -7.4422) (xy 5.300472 -7.4422) (xy 5.300472 7.4422)
				(xy 4.249928 7.4422) (xy 4.249928 7.800086)
			)
			(stroke
				(width 0)
				(type default)
			)
			(fill no)
			(layer "F.CrtYd")
		)
		(fp_line
			(start 4.249928 -7.800086)
			(end -4.249928 -7.800086)
			(stroke
				(width 0.1)
				(type default)
			)
			(layer "F.Fab")
		)
		(fp_line
			(start -4.249928 -7.800086)
			(end -4.249928 7.800086)
			(stroke
				(width 0.1)
				(type default)
			)
			(layer "F.Fab")
		)
		(fp_line
			(start 4.249928 7.800086)
			(end 4.249928 -7.800086)
			(stroke
				(width 0.1)
				(type default)
			)
			(layer "F.Fab")
		)
		(fp_line
			(start -4.249928 7.800086)
			(end 4.249928 7.800086)
			(stroke
				(width 0.1)
				(type default)
			)
			(layer "F.Fab")
		)
		(fp_poly
			(pts
				(xy -6.477 -7.493) (xy -6.477 -6.477) (xy -5.461 -6.985)
			)
			(stroke
				(width 0)
				(type default)
			)
			(fill yes)
			(layer "F.Fab")
		)
		(pad "1" smd rect
			(at -4.474972 -6.985)
			(size 0.8128 1.5494)
			(layers "F.Cu" "F.Mask" "F.Paste")
			(net "LAN2_MDI0_DP")
		)
		(pad "2" smd rect
			(at -4.474972 -5.715)
			(size 0.8128 1.5494)
			(layers "F.Cu" "F.Mask" "F.Paste")
			(net "LAN2_MDI0_DN")
		)
		(pad "3" smd rect
			(at -4.474972 -4.445)
			(size 0.8128 1.5494)
			(layers "F.Cu" "F.Mask" "F.Paste")
			(net "P1V9_LAN2")
		)
		(pad "4" smd rect
			(at -4.474972 -3.175)
			(size 0.8128 1.5494)
			(layers "F.Cu" "F.Mask" "F.Paste")
			(net "P1V9_LAN2")
		)
		(pad "5" smd rect
			(at -4.474972 -1.905)
			(size 0.8128 1.5494)
			(layers "F.Cu" "F.Mask" "F.Paste")
			(net "LAN2_MDI1_DP")
		)
		(pad "6" smd rect
			(at -4.474972 -0.635)
			(size 0.8128 1.5494)
			(layers "F.Cu" "F.Mask" "F.Paste")
			(net "LAN2_MDI1_DN")
		)
		(pad "7" smd rect
			(at -4.474972 0.635)
			(size 0.8128 1.5494)
			(layers "F.Cu" "F.Mask" "F.Paste")
			(net "LAN2_MDI2_DP")
		)
		(pad "8" smd rect
			(at -4.474972 1.905)
			(size 0.8128 1.5494)
			(layers "F.Cu" "F.Mask" "F.Paste")
			(net "LAN2_MDI2_DN")
		)
		(pad "9" smd rect
			(at -4.474972 3.175)
			(size 0.8128 1.5494)
			(layers "F.Cu" "F.Mask" "F.Paste")
			(net "P1V9_LAN2")
		)
		(pad "10" smd rect
			(at -4.474972 4.445)
			(size 0.8128 1.5494)
			(layers "F.Cu" "F.Mask" "F.Paste")
			(net "P1V9_LAN2")
		)
		(pad "11" smd rect
			(at -4.474972 5.715)
			(size 0.8128 1.5494)
			(layers "F.Cu" "F.Mask" "F.Paste")
			(net "LAN2_MDI3_DP")
		)
		(pad "12" smd rect
			(at -4.474972 6.985)
			(size 0.8128 1.5494)
			(layers "F.Cu" "F.Mask" "F.Paste")
			(net "LAN2_MDI3_DN")
		)
		(pad "13" smd rect
			(at 4.474972 6.985)
			(size 0.8128 1.5494)
			(layers "F.Cu" "F.Mask" "F.Paste")
			(net "LAN2_P4_N")
		)
		(pad "14" smd rect
			(at 4.474972 5.715)
			(size 0.8128 1.5494)
			(layers "F.Cu" "F.Mask" "F.Paste")
			(net "LAN2_P4_P")
		)
		(pad "15" smd rect
			(at 4.474972 4.445)
			(size 0.8128 1.5494)
			(layers "F.Cu" "F.Mask" "F.Paste")
			(net "LAN2_P4_R")
		)
		(pad "16" smd rect
			(at 4.474972 3.175)
			(size 0.8128 1.5494)
			(layers "F.Cu" "F.Mask" "F.Paste")
			(net "LAN2_P3_R")
		)
		(pad "17" smd rect
			(at 4.474972 1.905)
			(size 0.8128 1.5494)
			(layers "F.Cu" "F.Mask" "F.Paste")
			(net "LAN2_P3_N")
		)
		(pad "18" smd rect
			(at 4.474972 0.635)
			(size 0.8128 1.5494)
			(layers "F.Cu" "F.Mask" "F.Paste")
			(net "LAN2_P3_P")
		)
		(pad "19" smd rect
			(at 4.474972 -0.635)
			(size 0.8128 1.5494)
			(layers "F.Cu" "F.Mask" "F.Paste")
			(net "LAN2_P2_N")
		)
		(pad "20" smd rect
			(at 4.474972 -1.905)
			(size 0.8128 1.5494)
			(layers "F.Cu" "F.Mask" "F.Paste")
			(net "LAN2_P2_P")
		)
		(pad "21" smd rect
			(at 4.474972 -3.175)
			(size 0.8128 1.5494)
			(layers "F.Cu" "F.Mask" "F.Paste")
			(net "LAN2_P2_R")
		)
		(pad "22" smd rect
			(at 4.474972 -4.445)
			(size 0.8128 1.5494)
			(layers "F.Cu" "F.Mask" "F.Paste")
			(net "LAN2_P1_R")
		)
		(pad "23" smd rect
			(at 4.474972 -5.715)
			(size 0.8128 1.5494)
			(layers "F.Cu" "F.Mask" "F.Paste")
			(net "LAN2_P1_N")
		)
		(pad "24" smd rect
			(at 4.474972 -6.985)
			(size 0.8128 1.5494)
			(layers "F.Cu" "F.Mask" "F.Paste")
			(net "LAN2_P1_P")
		)
	)
	(footprint ""
		(layer "F.Cu")
		(at 72.24776 -188.126624 90)
		(property "Reference" "C710"
			(at 4.548886 -1.035558 90)
			(unlocked yes)
			(layer "F.SilkS")
			(effects
				(font
					(size 0.7874 0.5842)
					(thickness 0.1524)
				)
				(justify left)
			)
		)
		(property "Value" ""
			(at 0 0 90)
			(layer "F.Fab")
			(effects
				(font
					(size 1.27 1.27)
				)
			)
		)
		(duplicate_pad_numbers_are_jumpers no)
		(fp_line
			(start 0.7874 -0.4064)
			(end 0.7874 0.4064)
			(stroke
				(width 0.1524)
				(type default)
			)
			(layer "F.SilkS")
		)
		(fp_line
			(start -0.7874 -0.4064)
			(end 0.7874 -0.4064)
			(stroke
				(width 0.1524)
				(type default)
			)
			(layer "F.SilkS")
		)
		(fp_line
			(start 0 0.381)
			(end 0 -0.381)
			(stroke
				(width 0.1524)
				(type default)
			)
			(layer "F.SilkS")
		)
		(fp_line
			(start 0.7874 0.4064)
			(end -0.7874 0.4064)
			(stroke
				(width 0.1524)
				(type default)
			)
			(layer "F.SilkS")
		)
		(fp_line
			(start -0.7874 0.4064)
			(end -0.7874 -0.4064)
			(stroke
				(width 0.1524)
				(type default)
			)
			(layer "F.SilkS")
		)
		(fp_poly
			(pts
				(xy -0.5334 0.254) (xy -0.635 0.254) (xy -0.635 0.2286) (xy -0.635 -0.254) (xy -0.5334 -0.254) (xy -0.5334 -0.2794)
				(xy 0.5334 -0.2794) (xy 0.5334 -0.254) (xy 0.635 -0.254) (xy 0.635 0.254) (xy 0.5334 0.254) (xy 0.5334 0.2794)
				(xy -0.508 0.2794) (xy -0.5334 0.2794)
			)
			(stroke
				(width 0)
				(type default)
			)
			(fill no)
			(layer "F.CrtYd")
		)
		(pad "1" smd rect
			(at 0.40005 0 90)
			(size 0.4572 0.508)
			(layers "F.Cu" "F.Mask" "F.Paste")
			(net "UART_T4_NODE3_TXD_R")
		)
		(pad "2" smd rect
			(at -0.40005 0 90)
			(size 0.4572 0.508)
			(layers "F.Cu" "F.Mask" "F.Paste")
			(net "GND")
		)
	)
)
